(kicad_pcb
	(version 20260206)
	(generator "pcbnew")
	(generator_version "10.0")
	(general
		(thickness 1.6)
		(legacy_teardrops no)
	)
	(paper "A4")
	(title_block
		(title "Wiwynn_Tioga_Pass_MB.brd")
		(comment 1 "Tioga Pass / footprints 4198-4204 of 4770")
	)
	(layers
		(0 "F.Cu" signal "TOP")
		(4 "In1.Cu" signal "L2GND")
		(6 "In2.Cu" signal "L3")
		(8 "In3.Cu" signal "L4GND")
		(10 "In4.Cu" signal "L5")
		(12 "In5.Cu" signal "L6GND")
		(14 "In6.Cu" signal "L7VCC")
		(16 "In7.Cu" signal "L8VCC")
		(18 "In8.Cu" signal "L9GND")
		(20 "In9.Cu" signal "L10")
		(22 "In10.Cu" signal "L11GND")
		(24 "In11.Cu" signal "L12")
		(26 "In12.Cu" signal "L13GND")
		(2 "B.Cu" signal "BOTTOM")
		(9 "F.Adhes" user "F.Adhesive")
		(11 "B.Adhes" user "B.Adhesive")
		(13 "F.Paste" user "Package Geometry/Pastemask Top")
		(15 "B.Paste" user "Package Geometry/Pastemask Bottom")
		(5 "F.SilkS" user "Ref Des/Silkscreen Top")
		(7 "B.SilkS" user "Ref Des/Silkscreen Bottom")
		(1 "F.Mask" user "Board Geometry/Soldermask Top")
		(3 "B.Mask" user "Board Geometry/Soldermask Bottom")
		(17 "Dwgs.User" user "User.Drawings")
		(19 "Cmts.User" user "User.Comments")
		(21 "Eco1.User" user "User.Eco1")
		(23 "Eco2.User" user "User.Eco2")
		(25 "Edge.Cuts" user "Board Geometry/Outline")
		(27 "Margin" user)
		(31 "F.CrtYd" user "Package Geometry/Place Bound Top")
		(29 "B.CrtYd" user "Package Geometry/Place Bound Bottom")
		(35 "F.Fab" user "Ref Des/Assembly Top")
		(33 "B.Fab" user "Ref Des/Assembly Bottom")
	)
	(footprint ""
		(layer "B.Cu")
		(at 368.709956 -122.560842 -90)
		(property "Reference" "C3M33"
			(at 0 0 90)
			(layer "B.SilkS")
			(hide yes)
			(effects
				(font
					(size 1.27 1.27)
				)
				(justify mirror)
			)
		)
		(property "Value" ""
			(at 0 0 90)
			(layer "B.Fab")
			(effects
				(font
					(size 1.27 1.27)
				)
				(justify mirror)
			)
		)
		(duplicate_pad_numbers_are_jumpers no)
		(fp_poly
			(pts
				(xy -0.3048 -0.1016) (xy -0.3048 0.9906) (xy 0.3048 0.9906) (xy 0.3048 -0.1016)
			)
			(stroke
				(width 0)
				(type default)
			)
			(fill no)
			(layer "B.CrtYd")
		)
		(fp_line
			(start -0.3048 0.9906)
			(end -0.3048 -0.1016)
			(stroke
				(width 0.1)
				(type default)
			)
			(layer "B.Fab")
		)
		(fp_line
			(start 0.3048 0.9906)
			(end -0.3048 0.9906)
			(stroke
				(width 0.1)
				(type default)
			)
			(layer "B.Fab")
		)
		(fp_line
			(start -0.3048 -0.1016)
			(end 0.3048 -0.1016)
			(stroke
				(width 0.1)
				(type default)
			)
			(layer "B.Fab")
		)
		(fp_line
			(start 0.3048 -0.1016)
			(end 0.3048 0.9906)
			(stroke
				(width 0.1)
				(type default)
			)
			(layer "B.Fab")
		)
		(pad "1" smd rect
			(at 0 0 90)
			(size 0.508 0.508)
			(layers "B.Cu" "B.Mask" "B.Paste")
			(net "P3E_CPU0_PE1_PCH_R_RXN<8>")
		)
		(pad "2" smd rect
			(at 0 0.889 90)
			(size 0.508 0.508)
			(layers "B.Cu" "B.Mask" "B.Paste")
			(net "P3E_CPU0_PE1_PCH_RXN<8>")
		)
		(zone
			(layer "B.Cu")
			(hatch none 0.5)
			(connect_pads
				(clearance 0)
			)
			(min_thickness 0.25)
			(keepout
				(tracks not_allowed)
				(vias allowed)
				(pads allowed)
				(copperpour not_allowed)
				(footprints allowed)
			)
			(placement
				(enabled no)
				(sheetname "")
			)
			(fill
				(thermal_gap 0.5)
				(thermal_bridge_width 0.5)
				(island_removal_mode 0)
			)
			(polygon
				(pts
					(xy 368.074956 -122.306842) (xy 368.074956 -122.814842) (xy 368.455956 -122.814842) (xy 368.455956 -122.306842)
				)
			)
		)
		(zone
			(layer "B.Cu")
			(hatch none 0.5)
			(connect_pads
				(clearance 0)
			)
			(min_thickness 0.25)
			(keepout
				(tracks allowed)
				(vias not_allowed)
				(pads allowed)
				(copperpour not_allowed)
				(footprints allowed)
			)
			(placement
				(enabled no)
				(sheetname "")
			)
			(fill
				(thermal_gap 0.5)
				(thermal_bridge_width 0.5)
				(island_removal_mode 0)
			)
			(polygon
				(pts
					(xy 368.455956 -122.306842) (xy 368.455956 -122.814842) (xy 368.074956 -122.814842) (xy 368.074956 -122.306842)
				)
			)
		)
	)
	(footprint ""
		(layer "B.Cu")
		(at 194.437 -145.3642)
		(property "Reference" "R6L12"
			(at 0 0 0)
			(layer "B.SilkS")
			(hide yes)
			(effects
				(font
					(size 1.27 1.27)
				)
				(justify mirror)
			)
		)
		(property "Value" ""
			(at 0 0 0)
			(layer "B.Fab")
			(effects
				(font
					(size 1.27 1.27)
				)
				(justify mirror)
			)
		)
		(duplicate_pad_numbers_are_jumpers no)
		(fp_poly
			(pts
				(xy 0.2794 -0.1016) (xy -0.2794 -0.1016) (xy -0.2794 0.9906) (xy 0.2794 0.9906)
			)
			(stroke
				(width 0)
				(type default)
			)
			(fill no)
			(layer "B.CrtYd")
		)
		(fp_line
			(start -0.2794 -0.1016)
			(end 0.2794 -0.1016)
			(stroke
				(width 0.1)
				(type default)
			)
			(layer "B.Fab")
		)
		(fp_line
			(start -0.2794 0.9906)
			(end -0.2794 -0.1016)
			(stroke
				(width 0.1)
				(type default)
			)
			(layer "B.Fab")
		)
		(fp_line
			(start 0.2794 -0.1016)
			(end 0.2794 0.9906)
			(stroke
				(width 0.1)
				(type default)
			)
			(layer "B.Fab")
		)
		(fp_line
			(start 0.2794 0.9906)
			(end -0.2794 0.9906)
			(stroke
				(width 0.1)
				(type default)
			)
			(layer "B.Fab")
		)
		(pad "1" smd rect
			(at 0 0 180)
			(size 0.508 0.508)
			(layers "B.Cu" "B.Mask" "B.Paste")
			(net "M_E_VREF")
		)
		(pad "2" smd rect
			(at 0 0.889 180)
			(size 0.508 0.508)
			(layers "B.Cu" "B.Mask" "B.Paste")
			(net "GND")
		)
		(zone
			(layer "B.Cu")
			(hatch none 0.5)
			(connect_pads
				(clearance 0)
			)
			(min_thickness 0.25)
			(keepout
				(tracks allowed)
				(vias not_allowed)
				(pads allowed)
				(copperpour not_allowed)
				(footprints allowed)
			)
			(placement
				(enabled no)
				(sheetname "")
			)
			(fill
				(thermal_gap 0.5)
				(thermal_bridge_width 0.5)
				(island_removal_mode 0)
			)
			(polygon
				(pts
					(xy 194.691 -145.1102) (xy 194.183 -145.1102) (xy 194.183 -144.7292) (xy 194.691 -144.7292)
				)
			)
		)
		(zone
			(layer "B.Cu")
			(hatch none 0.5)
			(connect_pads
				(clearance 0)
			)
			(min_thickness 0.25)
			(keepout
				(tracks not_allowed)
				(vias allowed)
				(pads allowed)
				(copperpour not_allowed)
				(footprints allowed)
			)
			(placement
				(enabled no)
				(sheetname "")
			)
			(fill
				(thermal_gap 0.5)
				(thermal_bridge_width 0.5)
				(island_removal_mode 0)
			)
			(polygon
				(pts
					(xy 194.691 -144.7292) (xy 194.183 -144.7292) (xy 194.183 -145.1102) (xy 194.691 -145.1102)
				)
			)
		)
	)
	(footprint ""
		(layer "B.Cu")
		(at 341.666068 -77.694536 180)
		(property "Reference" "C3P15"
			(at 0 0 0)
			(layer "B.SilkS")
			(hide yes)
			(effects
				(font
					(size 1.27 1.27)
				)
				(justify mirror)
			)
		)
		(property "Value" ""
			(at 0 0 0)
			(layer "B.Fab")
			(effects
				(font
					(size 1.27 1.27)
				)
				(justify mirror)
			)
		)
		(duplicate_pad_numbers_are_jumpers no)
		(fp_poly
			(pts
				(xy -0.3048 -0.1016) (xy -0.3048 0.9906) (xy 0.3048 0.9906) (xy 0.3048 -0.1016)
			)
			(stroke
				(width 0)
				(type default)
			)
			(fill no)
			(layer "B.CrtYd")
		)
		(fp_line
			(start 0.3048 0.9906)
			(end -0.3048 0.9906)
			(stroke
				(width 0.1)
				(type default)
			)
			(layer "B.Fab")
		)
		(fp_line
			(start 0.3048 -0.1016)
			(end 0.3048 0.9906)
			(stroke
				(width 0.1)
				(type default)
			)
			(layer "B.Fab")
		)
		(fp_line
			(start -0.3048 0.9906)
			(end -0.3048 -0.1016)
			(stroke
				(width 0.1)
				(type default)
			)
			(layer "B.Fab")
		)
		(fp_line
			(start -0.3048 -0.1016)
			(end 0.3048 -0.1016)
			(stroke
				(width 0.1)
				(type default)
			)
			(layer "B.Fab")
		)
		(pad "1" smd rect
			(at 0 0)
			(size 0.508 0.508)
			(layers "B.Cu" "B.Mask" "B.Paste")
			(net "P3E_CPU0_PE1_SS_TXP<1>")
		)
		(pad "2" smd rect
			(at 0 0.889)
			(size 0.508 0.508)
			(layers "B.Cu" "B.Mask" "B.Paste")
			(net "P3E_CPU0_PE1_PCH_TXP<1>")
		)
		(zone
			(layer "B.Cu")
			(hatch none 0.5)
			(connect_pads
				(clearance 0)
			)
			(min_thickness 0.25)
			(keepout
				(tracks not_allowed)
				(vias allowed)
				(pads allowed)
				(copperpour not_allowed)
				(footprints allowed)
			)
			(placement
				(enabled no)
				(sheetname "")
			)
			(fill
				(thermal_gap 0.5)
				(thermal_bridge_width 0.5)
				(island_removal_mode 0)
			)
			(polygon
				(pts
					(xy 341.412068 -78.329536) (xy 341.920068 -78.329536) (xy 341.920068 -77.948536) (xy 341.412068 -77.948536)
				)
			)
		)
		(zone
			(layer "B.Cu")
			(hatch none 0.5)
			(connect_pads
				(clearance 0)
			)
			(min_thickness 0.25)
			(keepout
				(tracks allowed)
				(vias not_allowed)
				(pads allowed)
				(copperpour not_allowed)
				(footprints allowed)
			)
			(placement
				(enabled no)
				(sheetname "")
			)
			(fill
				(thermal_gap 0.5)
				(thermal_bridge_width 0.5)
				(island_removal_mode 0)
			)
			(polygon
				(pts
					(xy 341.412068 -77.948536) (xy 341.920068 -77.948536) (xy 341.920068 -78.329536) (xy 341.412068 -78.329536)
				)
			)
		)
	)
	(footprint ""
		(layer "B.Cu")
		(at 379.3998 -46.2026 180)
		(property "Reference" "C7E4"
			(at 0 0 0)
			(layer "B.SilkS")
			(hide yes)
			(effects
				(font
					(size 1.27 1.27)
				)
				(justify mirror)
			)
		)
		(property "Value" ""
			(at 0 0 0)
			(layer "B.Fab")
			(effects
				(font
					(size 1.27 1.27)
				)
				(justify mirror)
			)
		)
		(duplicate_pad_numbers_are_jumpers no)
		(fp_poly
			(pts
				(xy -0.3048 -0.1016) (xy -0.3048 0.9906) (xy 0.3048 0.9906) (xy 0.3048 -0.1016)
			)
			(stroke
				(width 0)
				(type default)
			)
			(fill no)
			(layer "B.CrtYd")
		)
		(fp_line
			(start 0.3048 0.9906)
			(end -0.3048 0.9906)
			(stroke
				(width 0.1)
				(type default)
			)
			(layer "B.Fab")
		)
		(fp_line
			(start 0.3048 -0.1016)
			(end 0.3048 0.9906)
			(stroke
				(width 0.1)
				(type default)
			)
			(layer "B.Fab")
		)
		(fp_line
			(start -0.3048 0.9906)
			(end -0.3048 -0.1016)
			(stroke
				(width 0.1)
				(type default)
			)
			(layer "B.Fab")
		)
		(fp_line
			(start -0.3048 -0.1016)
			(end 0.3048 -0.1016)
			(stroke
				(width 0.1)
				(type default)
			)
			(layer "B.Fab")
		)
		(pad "1" smd rect
			(at 0 0)
			(size 0.508 0.508)
			(layers "B.Cu" "B.Mask" "B.Paste")
			(net "P3V3_STBY")
		)
		(pad "2" smd rect
			(at 0 0.889)
			(size 0.508 0.508)
			(layers "B.Cu" "B.Mask" "B.Paste")
			(net "GND")
		)
		(zone
			(layer "B.Cu")
			(hatch none 0.5)
			(connect_pads
				(clearance 0)
			)
			(min_thickness 0.25)
			(keepout
				(tracks not_allowed)
				(vias allowed)
				(pads allowed)
				(copperpour not_allowed)
				(footprints allowed)
			)
			(placement
				(enabled no)
				(sheetname "")
			)
			(fill
				(thermal_gap 0.5)
				(thermal_bridge_width 0.5)
				(island_removal_mode 0)
			)
			(polygon
				(pts
					(xy 379.1458 -46.8376) (xy 379.6538 -46.8376) (xy 379.6538 -46.4566) (xy 379.1458 -46.4566)
				)
			)
		)
		(zone
			(layer "B.Cu")
			(hatch none 0.5)
			(connect_pads
				(clearance 0)
			)
			(min_thickness 0.25)
			(keepout
				(tracks allowed)
				(vias not_allowed)
				(pads allowed)
				(copperpour not_allowed)
				(footprints allowed)
			)
			(placement
				(enabled no)
				(sheetname "")
			)
			(fill
				(thermal_gap 0.5)
				(thermal_bridge_width 0.5)
				(island_removal_mode 0)
			)
			(polygon
				(pts
					(xy 379.1458 -46.4566) (xy 379.6538 -46.4566) (xy 379.6538 -46.8376) (xy 379.1458 -46.8376)
				)
			)
		)
	)
	(footprint ""
		(layer "B.Cu")
		(at 390.93775 -114.25555 180)
		(property "Reference" "C2M18"
			(at 0 0 0)
			(layer "B.SilkS")
			(hide yes)
			(effects
				(font
					(size 1.27 1.27)
				)
				(justify mirror)
			)
		)
		(property "Value" ""
			(at 0 0 0)
			(layer "B.Fab")
			(effects
				(font
					(size 1.27 1.27)
				)
				(justify mirror)
			)
		)
		(duplicate_pad_numbers_are_jumpers no)
		(fp_rect
			(start 0.2794 0.9144)
			(end -0.2794 -0.1143)
			(stroke
				(width 0)
				(type default)
			)
			(fill no)
			(layer "B.CrtYd")
		)
		(fp_line
			(start 0.2794 0.9144)
			(end 0.2794 -0.1143)
			(stroke
				(width 0.1)
				(type default)
			)
			(layer "B.Fab")
		)
		(fp_line
			(start 0.2794 -0.1143)
			(end -0.2794 -0.1143)
			(stroke
				(width 0.1)
				(type default)
			)
			(layer "B.Fab")
		)
		(fp_line
			(start -0.2794 0.9144)
			(end 0.2794 0.9144)
			(stroke
				(width 0.1)
				(type default)
			)
			(layer "B.Fab")
		)
		(fp_line
			(start -0.2794 -0.1143)
			(end -0.2794 0.9144)
			(stroke
				(width 0.1)
				(type default)
			)
			(layer "B.Fab")
		)
		(pad "1" smd custom
			(at 0 0 90)
			(size 0.10414 0.10414)
			(layers "B.Cu" "B.Mask" "B.Paste")
			(net "P1V05_PCH_STBY")
			(options
				(clearance outline)
				(anchor circle)
			)
			(primitives
				(gr_poly
					(pts
						(xy -0.20828 -0.08636) (xy -0.20828 0.08636) (xy -0.08636 0.20828) (xy 0.086614 0.20828) (xy 0.20828 0.086614)
						(xy 0.20828 -0.08636) (xy 0.08636 -0.20828) (xy -0.08636 -0.20828)
					)
					(width 0)
					(fill yes)
				)
			)
		)
		(pad "2" smd custom
			(at 0 0.8001 90)
			(size 0.10414 0.10414)
			(layers "B.Cu" "B.Mask" "B.Paste")
			(net "GND")
			(options
				(clearance outline)
				(anchor circle)
			)
			(primitives
				(gr_poly
					(pts
						(xy -0.20828 -0.08636) (xy -0.20828 0.08636) (xy -0.08636 0.20828) (xy 0.086614 0.20828) (xy 0.20828 0.086614)
						(xy 0.20828 -0.08636) (xy 0.08636 -0.20828) (xy -0.08636 -0.20828)
					)
					(width 0)
					(fill yes)
				)
			)
		)
		(zone
			(layer "B.Cu")
			(hatch none 0.5)
			(connect_pads
				(clearance 0)
			)
			(min_thickness 0.25)
			(keepout
				(tracks not_allowed)
				(vias allowed)
				(pads allowed)
				(copperpour not_allowed)
				(footprints allowed)
			)
			(placement
				(enabled no)
				(sheetname "")
			)
			(fill
				(thermal_gap 0.5)
				(thermal_bridge_width 0.5)
				(island_removal_mode 0)
			)
			(polygon
				(pts
					(xy 390.85012 -114.4651) (xy 390.85012 -114.8461) (xy 391.02538 -114.8461) (xy 391.025634 -114.4651)
				)
			)
		)
		(zone
			(layer "B.Cu")
			(hatch none 0.5)
			(connect_pads
				(clearance 0)
			)
			(min_thickness 0.25)
			(keepout
				(tracks allowed)
				(vias not_allowed)
				(pads allowed)
				(copperpour not_allowed)
				(footprints allowed)
			)
			(placement
				(enabled no)
				(sheetname "")
			)
			(fill
				(thermal_gap 0.5)
				(thermal_bridge_width 0.5)
				(island_removal_mode 0)
			)
			(polygon
				(pts
					(xy 390.85012 -114.4651) (xy 390.85012 -114.8461) (xy 391.02538 -114.8461) (xy 391.025634 -114.4651)
				)
			)
		)
	)
	(footprint ""
		(layer "B.Cu")
		(at 276.000464 -140.208 90)
		(property "Reference" "C5G76"
			(at -1.14681 0.76708 180)
			(unlocked yes)
			(layer "B.SilkS")
			(effects
				(font
					(size 0.7874 0.5842)
					(thickness 0.1524)
				)
				(justify mirror)
			)
		)
		(property "Value" ""
			(at 0 0 90)
			(layer "B.Fab")
			(effects
				(font
					(size 1.27 1.27)
				)
				(justify mirror)
			)
		)
		(duplicate_pad_numbers_are_jumpers no)
		(fp_rect
			(start -0.4953 -0.2032)
			(end 0.4953 1.6002)
			(stroke
				(width 0)
				(type default)
			)
			(fill no)
			(layer "B.CrtYd")
		)
		(fp_line
			(start 0.4953 -0.2032)
			(end -0.4953 -0.2032)
			(stroke
				(width 0.1)
				(type default)
			)
			(layer "B.Fab")
		)
		(fp_line
			(start -0.4953 -0.2032)
			(end -0.4953 1.6002)
			(stroke
				(width 0.1)
				(type default)
			)
			(layer "B.Fab")
		)
		(fp_line
			(start 0.4953 1.6002)
			(end 0.4953 -0.2032)
			(stroke
				(width 0.1)
				(type default)
			)
			(layer "B.Fab")
		)
		(fp_line
			(start -0.4953 1.6002)
			(end 0.4953 1.6002)
			(stroke
				(width 0.1)
				(type default)
			)
			(layer "B.Fab")
		)
		(pad "1" smd rect
			(at 0 0 270)
			(size 0.762 0.889)
			(layers "B.Cu" "B.Mask" "B.Paste")
			(net "PVDDQ_DEF")
		)
		(pad "2" smd rect
			(at 0 1.397 270)
			(size 0.762 0.889)
			(layers "B.Cu" "B.Mask" "B.Paste")
			(net "GND")
		)
		(zone
			(layer "B.Cu")
			(hatch none 0.5)
			(connect_pads
				(clearance 0)
			)
			(min_thickness 0.25)
			(keepout
				(tracks not_allowed)
				(vias allowed)
				(pads allowed)
				(copperpour not_allowed)
				(footprints allowed)
			)
			(placement
				(enabled no)
				(sheetname "")
			)
			(fill
				(thermal_gap 0.5)
				(thermal_bridge_width 0.5)
				(island_removal_mode 0)
			)
			(polygon
				(pts
					(xy 276.444964 -139.827) (xy 276.952964 -139.827) (xy 276.952964 -140.589) (xy 276.444964 -140.589)
				)
			)
		)
	)
	(footprint ""
		(layer "B.Cu")
		(at 101.104192 -68.184014 180)
		(property "Reference" "C8P31"
			(at 0 0 0)
			(layer "B.SilkS")
			(hide yes)
			(effects
				(font
					(size 1.27 1.27)
				)
				(justify mirror)
			)
		)
		(property "Value" ""
			(at 0 0 0)
			(layer "B.Fab")
			(effects
				(font
					(size 1.27 1.27)
				)
				(justify mirror)
			)
		)
		(duplicate_pad_numbers_are_jumpers no)
		(fp_poly
			(pts
				(xy 0.7239 -0.2159) (xy -0.7239 -0.2159) (xy -0.7239 1.9939) (xy 0.7239 1.9939)
			)
			(stroke
				(width 0)
				(type default)
			)
			(fill no)
			(layer "B.CrtYd")
		)
		(fp_line
			(start 0.7239 1.9939)
			(end -0.7239 1.9939)
			(stroke
				(width 0.1)
				(type default)
			)
			(layer "B.Fab")
		)
		(fp_line
			(start 0.7239 -0.2159)
			(end 0.7239 1.9939)
			(stroke
				(width 0.1)
				(type default)
			)
			(layer "B.Fab")
		)
		(fp_line
			(start -0.7239 1.9939)
			(end -0.7239 -0.2159)
			(stroke
				(width 0.1)
				(type default)
			)
			(layer "B.Fab")
		)
		(fp_line
			(start -0.7239 -0.2159)
			(end 0.7239 -0.2159)
			(stroke
				(width 0.1)
				(type default)
			)
			(layer "B.Fab")
		)
		(pad "1" smd rect
			(at 0 0)
			(size 1.27 1.016)
			(layers "B.Cu" "B.Mask" "B.Paste")
			(net "PVDDQ_GHJ")
		)
		(pad "2" smd rect
			(at 0 1.778)
			(size 1.27 1.016)
			(layers "B.Cu" "B.Mask" "B.Paste")
			(net "GND")
		)
		(zone
			(layer "B.Cu")
			(hatch none 0.5)
			(connect_pads
				(clearance 0)
			)
			(min_thickness 0.25)
			(keepout
				(tracks not_allowed)
				(vias allowed)
				(pads allowed)
				(copperpour not_allowed)
				(footprints allowed)
			)
			(placement
				(enabled no)
				(sheetname "")
			)
			(fill
				(thermal_gap 0.5)
				(thermal_bridge_width 0.5)
				(island_removal_mode 0)
			)
			(polygon
				(pts
					(xy 100.469192 -68.692014) (xy 101.739192 -68.692014) (xy 101.739192 -69.454014) (xy 100.469192 -69.454014)
				)
			)
		)
	)
)
